(kicad_pcb
	(version 20260206)
	(generator "pcbnew")
	(generator_version "10.0")
	(general
		(thickness 1.6)
		(legacy_teardrops no)
	)
	(paper "A4")
	(title_block
		(title "peb — Lightning_PEB_BRD.brd")
		(comment 1 "Lightning (Wiwynn / Facebook NVMe JBOF) / footprints 217-224 of 2563")
	)
	(layers
		(0 "F.Cu" signal "TOP")
		(4 "In1.Cu" signal "L2GND")
		(6 "In2.Cu" signal "L3")
		(8 "In3.Cu" signal "L4VCC")
		(10 "In4.Cu" signal "L5VCC")
		(12 "In5.Cu" signal "L6")
		(14 "In6.Cu" signal "L7GND")
		(2 "B.Cu" signal "BOTTOM")
		(9 "F.Adhes" user "F.Adhesive")
		(11 "B.Adhes" user "B.Adhesive")
		(13 "F.Paste" user "Package Geometry/Pastemask Top")
		(15 "B.Paste" user "Package Geometry/Pastemask Bottom")
		(5 "F.SilkS" user "Ref Des/Silkscreen Top")
		(7 "B.SilkS" user "Ref Des/Silkscreen Bottom")
		(1 "F.Mask" user "Board Geometry/Soldermask Top")
		(3 "B.Mask" user "Board Geometry/Soldermask Bottom")
		(17 "Dwgs.User" user "User.Drawings")
		(19 "Cmts.User" user "User.Comments")
		(21 "Eco1.User" user "User.Eco1")
		(23 "Eco2.User" user "User.Eco2")
		(25 "Edge.Cuts" user "Board Geometry/Outline")
		(27 "Margin" user)
		(31 "F.CrtYd" user "Package Geometry/Place Bound Top")
		(29 "B.CrtYd" user "Package Geometry/Place Bound Bottom")
		(35 "F.Fab" user "Ref Des/Assembly Top")
		(33 "B.Fab" user "Ref Des/Assembly Bottom")
	)
	(footprint ""
		(layer "F.Cu")
		(at 323.723 -86.487)
		(property "Reference" "R4175"
			(at 0 0 0)
			(layer "F.SilkS")
			(hide yes)
			(effects
				(font
					(size 1.27 1.27)
				)
			)
		)
		(property "Value" "4K7R2F-GP"
			(at 0.064008 -3.993896 0)
			(unlocked yes)
			(layer "F.Fab")
			(hide yes)
			(effects
				(font
					(size 1.016 1.016)
					(thickness 0.1524)
				)
			)
		)
		(property "Device Type" "R402H16"
			(at 0.064008 -5.517896 0)
			(unlocked yes)
			(layer "F.Fab")
			(hide yes)
			(effects
				(font
					(size 1.016 1.016)
					(thickness 0.1524)
				)
			)
		)
		(duplicate_pad_numbers_are_jumpers no)
		(fp_line
			(start -0.508 -0.9398)
			(end -0.508 0.9398)
			(stroke
				(width 0.1524)
				(type default)
			)
			(layer "F.SilkS")
		)
		(fp_line
			(start 0.508 -0.9398)
			(end -0.508 -0.9398)
			(stroke
				(width 0.1524)
				(type default)
			)
			(layer "F.SilkS")
		)
		(fp_rect
			(start -0.508 0.9398)
			(end 0.508 -0.9398)
			(stroke
				(width 0)
				(type default)
			)
			(fill no)
			(layer "F.CrtYd")
		)
		(fp_rect
			(start -0.508 0.9398)
			(end 0.508 -0.9398)
			(stroke
				(width 0)
				(type default)
			)
			(fill no)
			(layer "F.Fab")
		)
		(pad "1" smd custom
			(at 0 -0.4445)
			(size 0.1397 0.1397)
			(layers "F.Cu" "F.Mask" "F.Paste")
			(net "UPLINK1")
			(options
				(clearance outline)
				(anchor circle)
			)
			(primitives
				(gr_poly
					(pts
						(arc
							(start -0.1778 -0.2794)
							(mid -0.249642 -0.249642)
							(end -0.2794 -0.1778)
						)
						(arc
							(start -0.2794 0.1778)
							(mid -0.249642 0.249642)
							(end -0.1778 0.2794)
						)
						(arc
							(start 0.1778 0.2794)
							(mid 0.249642 0.249642)
							(end 0.2794 0.1778)
						)
						(arc
							(start 0.2794 -0.1778)
							(mid 0.249642 -0.249642)
							(end 0.1778 -0.2794)
						)
					)
					(width 0)
					(fill yes)
				)
			)
		)
		(pad "2" smd custom
			(at 0 0.4445)
			(size 0.1397 0.1397)
			(layers "F.Cu" "F.Mask" "F.Paste")
			(net "P3V3_STBY")
			(options
				(clearance outline)
				(anchor circle)
			)
			(primitives
				(gr_poly
					(pts
						(arc
							(start -0.1778 -0.2794)
							(mid -0.249642 -0.249642)
							(end -0.2794 -0.1778)
						)
						(arc
							(start -0.2794 0.1778)
							(mid -0.249642 0.249642)
							(end -0.1778 0.2794)
						)
						(arc
							(start 0.1778 0.2794)
							(mid 0.249642 0.249642)
							(end 0.2794 0.1778)
						)
						(arc
							(start 0.2794 -0.1778)
							(mid 0.249642 -0.249642)
							(end 0.1778 -0.2794)
						)
					)
					(width 0)
					(fill yes)
				)
			)
		)
	)
	(footprint ""
		(layer "F.Cu")
		(at 177.008028 -212.420454 180)
		(property "Reference" "C137"
			(at 0 0 180)
			(layer "F.SilkS")
			(hide yes)
			(effects
				(font
					(size 1.27 1.27)
				)
			)
		)
		(property "Value" "SCD22U10V2KX-1GP"
			(at 1.1811 -2.7051 180)
			(unlocked yes)
			(layer "F.Fab")
			(hide yes)
			(effects
				(font
					(size 1.016 1.016)
					(thickness 0.1524)
				)
			)
		)
		(property "Device Type" "C402H22"
			(at 1.1811 -4.2291 180)
			(unlocked yes)
			(layer "F.Fab")
			(hide yes)
			(effects
				(font
					(size 1.016 1.016)
					(thickness 0.1524)
				)
			)
		)
		(duplicate_pad_numbers_are_jumpers no)
		(fp_rect
			(start -0.4318 0.9525)
			(end 0.4318 -0.9525)
			(stroke
				(width 0)
				(type default)
			)
			(fill no)
			(layer "F.CrtYd")
		)
		(fp_rect
			(start -0.4318 0.9525)
			(end 0.4318 -0.9525)
			(stroke
				(width 0)
				(type default)
			)
			(fill no)
			(layer "F.Fab")
		)
		(pad "1" smd custom
			(at 0 -0.4445 180)
			(size 0.1524 0.1524)
			(layers "F.Cu" "F.Mask" "F.Paste")
			(net "PCIE_TX_CAP_N48")
			(options
				(clearance outline)
				(anchor circle)
			)
			(primitives
				(gr_poly
					(pts
						(arc
							(start 0.3048 -0.2032)
							(mid 0.275042 -0.275042)
							(end 0.2032 -0.3048)
						)
						(arc
							(start -0.2032 -0.3048)
							(mid -0.275042 -0.275042)
							(end -0.3048 -0.2032)
						)
						(arc
							(start -0.3048 0.2032)
							(mid -0.275042 0.275042)
							(end -0.2032 0.3048)
						)
						(arc
							(start 0.2032 0.3048)
							(mid 0.275042 0.275042)
							(end 0.3048 0.2032)
						)
					)
					(width 0)
					(fill yes)
				)
			)
		)
		(pad "2" smd custom
			(at 0 0.4445 180)
			(size 0.1524 0.1524)
			(layers "F.Cu" "F.Mask" "F.Paste")
			(net "PCIE_TX_N48")
			(options
				(clearance outline)
				(anchor circle)
			)
			(primitives
				(gr_poly
					(pts
						(arc
							(start 0.3048 -0.2032)
							(mid 0.275042 -0.275042)
							(end 0.2032 -0.3048)
						)
						(arc
							(start -0.2032 -0.3048)
							(mid -0.275042 -0.275042)
							(end -0.3048 -0.2032)
						)
						(arc
							(start -0.3048 0.2032)
							(mid -0.275042 0.275042)
							(end -0.2032 0.3048)
						)
						(arc
							(start 0.2032 0.3048)
							(mid 0.275042 0.275042)
							(end 0.3048 0.2032)
						)
					)
					(width 0)
					(fill yes)
				)
			)
		)
	)
	(footprint ""
		(layer "F.Cu")
		(at 273.702526 -5.7023 -90)
		(property "Reference" "R2911"
			(at 0 0 270)
			(layer "F.SilkS")
			(hide yes)
			(effects
				(font
					(size 1.27 1.27)
				)
			)
		)
		(property "Value" "0R2J-2-GP"
			(at 0.064008 -3.993896 270)
			(unlocked yes)
			(layer "F.Fab")
			(hide yes)
			(effects
				(font
					(size 1.016 1.016)
					(thickness 0.1524)
				)
			)
		)
		(property "Device Type" "R402H16"
			(at 0.064008 -5.517896 270)
			(unlocked yes)
			(layer "F.Fab")
			(hide yes)
			(effects
				(font
					(size 1.016 1.016)
					(thickness 0.1524)
				)
			)
		)
		(duplicate_pad_numbers_are_jumpers no)
		(fp_line
			(start -0.508 -0.9398)
			(end -0.508 0.9398)
			(stroke
				(width 0.1524)
				(type default)
			)
			(layer "F.SilkS")
		)
		(fp_line
			(start 0.508 -0.9398)
			(end -0.508 -0.9398)
			(stroke
				(width 0.1524)
				(type default)
			)
			(layer "F.SilkS")
		)
		(fp_rect
			(start -0.508 0.9398)
			(end 0.508 -0.9398)
			(stroke
				(width 0)
				(type default)
			)
			(fill no)
			(layer "F.CrtYd")
		)
		(fp_rect
			(start -0.508 0.9398)
			(end 0.508 -0.9398)
			(stroke
				(width 0)
				(type default)
			)
			(fill no)
			(layer "F.Fab")
		)
		(pad "1" smd custom
			(at 0 -0.4445 270)
			(size 0.1397 0.1397)
			(layers "F.Cu" "F.Mask" "F.Paste")
			(net "CBL_PRSNT_N_6")
			(options
				(clearance outline)
				(anchor circle)
			)
			(primitives
				(gr_poly
					(pts
						(arc
							(start -0.1778 -0.2794)
							(mid -0.249642 -0.249642)
							(end -0.2794 -0.1778)
						)
						(arc
							(start -0.2794 0.1778)
							(mid -0.249642 0.249642)
							(end -0.1778 0.2794)
						)
						(arc
							(start 0.1778 0.2794)
							(mid 0.249642 0.249642)
							(end 0.2794 0.1778)
						)
						(arc
							(start 0.2794 -0.1778)
							(mid 0.249642 -0.249642)
							(end 0.1778 -0.2794)
						)
					)
					(width 0)
					(fill yes)
				)
			)
		)
		(pad "2" smd custom
			(at 0 0.4445 270)
			(size 0.1397 0.1397)
			(layers "F.Cu" "F.Mask" "F.Paste")
			(net "8644_SDA_R_6")
			(options
				(clearance outline)
				(anchor circle)
			)
			(primitives
				(gr_poly
					(pts
						(arc
							(start -0.1778 -0.2794)
							(mid -0.249642 -0.249642)
							(end -0.2794 -0.1778)
						)
						(arc
							(start -0.2794 0.1778)
							(mid -0.249642 0.249642)
							(end -0.1778 0.2794)
						)
						(arc
							(start 0.1778 0.2794)
							(mid 0.249642 0.249642)
							(end 0.2794 0.1778)
						)
						(arc
							(start 0.2794 -0.1778)
							(mid 0.249642 -0.249642)
							(end 0.1778 -0.2794)
						)
					)
					(width 0)
					(fill yes)
				)
			)
		)
	)
	(footprint ""
		(layer "F.Cu")
		(at 56.134 -132.08)
		(property "Reference" "C8086"
			(at 0 0 0)
			(layer "F.SilkS")
			(hide yes)
			(effects
				(font
					(size 1.27 1.27)
				)
			)
		)
		(property "Value" "SCD1U25V2KX-2-GP"
			(at 1.1811 -2.7051 0)
			(unlocked yes)
			(layer "F.Fab")
			(hide yes)
			(effects
				(font
					(size 1.016 1.016)
					(thickness 0.1524)
				)
			)
		)
		(property "Device Type" "C402H22"
			(at 1.1811 -4.2291 0)
			(unlocked yes)
			(layer "F.Fab")
			(hide yes)
			(effects
				(font
					(size 1.016 1.016)
					(thickness 0.1524)
				)
			)
		)
		(duplicate_pad_numbers_are_jumpers no)
		(fp_rect
			(start -0.4318 0.9525)
			(end 0.4318 -0.9525)
			(stroke
				(width 0)
				(type default)
			)
			(fill no)
			(layer "F.CrtYd")
		)
		(fp_rect
			(start -0.4318 0.9525)
			(end 0.4318 -0.9525)
			(stroke
				(width 0)
				(type default)
			)
			(fill no)
			(layer "F.Fab")
		)
		(pad "1" smd custom
			(at 0 -0.4445)
			(size 0.1524 0.1524)
			(layers "F.Cu" "F.Mask" "F.Paste")
			(net "ADC_P1V53V")
			(options
				(clearance outline)
				(anchor circle)
			)
			(primitives
				(gr_poly
					(pts
						(arc
							(start 0.3048 -0.2032)
							(mid 0.275042 -0.275042)
							(end 0.2032 -0.3048)
						)
						(arc
							(start -0.2032 -0.3048)
							(mid -0.275042 -0.275042)
							(end -0.3048 -0.2032)
						)
						(arc
							(start -0.3048 0.2032)
							(mid -0.275042 0.275042)
							(end -0.2032 0.3048)
						)
						(arc
							(start 0.2032 0.3048)
							(mid 0.275042 0.275042)
							(end 0.3048 0.2032)
						)
					)
					(width 0)
					(fill yes)
				)
			)
		)
		(pad "2" smd custom
			(at 0 0.4445)
			(size 0.1524 0.1524)
			(layers "F.Cu" "F.Mask" "F.Paste")
			(net "GND")
			(options
				(clearance outline)
				(anchor circle)
			)
			(primitives
				(gr_poly
					(pts
						(arc
							(start 0.3048 -0.2032)
							(mid 0.275042 -0.275042)
							(end 0.2032 -0.3048)
						)
						(arc
							(start -0.2032 -0.3048)
							(mid -0.275042 -0.275042)
							(end -0.3048 -0.2032)
						)
						(arc
							(start -0.3048 0.2032)
							(mid -0.275042 0.275042)
							(end -0.2032 0.3048)
						)
						(arc
							(start 0.2032 0.3048)
							(mid 0.275042 0.275042)
							(end 0.3048 0.2032)
						)
					)
					(width 0)
					(fill yes)
				)
			)
		)
	)
	(footprint ""
		(layer "F.Cu")
		(at 181.61 -26.797 -90)
		(property "Reference" "C407"
			(at 0 0 270)
			(layer "F.SilkS")
			(hide yes)
			(effects
				(font
					(size 1.27 1.27)
				)
			)
		)
		(property "Value" "SCD22U10V2KX-1GP"
			(at 1.1811 -2.7051 270)
			(unlocked yes)
			(layer "F.Fab")
			(hide yes)
			(effects
				(font
					(size 1.016 1.016)
					(thickness 0.1524)
				)
			)
		)
		(property "Device Type" "C402H22"
			(at 1.1811 -4.2291 270)
			(unlocked yes)
			(layer "F.Fab")
			(hide yes)
			(effects
				(font
					(size 1.016 1.016)
					(thickness 0.1524)
				)
			)
		)
		(duplicate_pad_numbers_are_jumpers no)
		(fp_rect
			(start -0.4318 0.9525)
			(end 0.4318 -0.9525)
			(stroke
				(width 0)
				(type default)
			)
			(fill no)
			(layer "F.CrtYd")
		)
		(fp_rect
			(start -0.4318 0.9525)
			(end 0.4318 -0.9525)
			(stroke
				(width 0)
				(type default)
			)
			(fill no)
			(layer "F.Fab")
		)
		(pad "1" smd custom
			(at 0 -0.4445 270)
			(size 0.1524 0.1524)
			(layers "F.Cu" "F.Mask" "F.Paste")
			(net "PCIE_TX_CAP_P93")
			(options
				(clearance outline)
				(anchor circle)
			)
			(primitives
				(gr_poly
					(pts
						(arc
							(start 0.3048 -0.2032)
							(mid 0.275042 -0.275042)
							(end 0.2032 -0.3048)
						)
						(arc
							(start -0.2032 -0.3048)
							(mid -0.275042 -0.275042)
							(end -0.3048 -0.2032)
						)
						(arc
							(start -0.3048 0.2032)
							(mid -0.275042 0.275042)
							(end -0.2032 0.3048)
						)
						(arc
							(start 0.2032 0.3048)
							(mid 0.275042 0.275042)
							(end 0.3048 0.2032)
						)
					)
					(width 0)
					(fill yes)
				)
			)
		)
		(pad "2" smd custom
			(at 0 0.4445 270)
			(size 0.1524 0.1524)
			(layers "F.Cu" "F.Mask" "F.Paste")
			(net "PCIE_TX_P93")
			(options
				(clearance outline)
				(anchor circle)
			)
			(primitives
				(gr_poly
					(pts
						(arc
							(start 0.3048 -0.2032)
							(mid 0.275042 -0.275042)
							(end 0.2032 -0.3048)
						)
						(arc
							(start -0.2032 -0.3048)
							(mid -0.275042 -0.275042)
							(end -0.3048 -0.2032)
						)
						(arc
							(start -0.3048 0.2032)
							(mid -0.275042 0.275042)
							(end -0.2032 0.3048)
						)
						(arc
							(start 0.2032 0.3048)
							(mid 0.275042 0.275042)
							(end 0.3048 0.2032)
						)
					)
					(width 0)
					(fill yes)
				)
			)
		)
	)
	(footprint ""
		(layer "F.Cu")
		(at 31.496 -195.199 90)
		(property "Reference" "D36"
			(at 0 0 90)
			(layer "F.SilkS")
			(hide yes)
			(effects
				(font
					(size 1.27 1.27)
				)
			)
		)
		(property "Value" "MM3Z15VT1G-GP-U"
			(at 0 -6.7818 90)
			(unlocked yes)
			(layer "F.Fab")
			(hide yes)
			(effects
				(font
					(size 1.016 1.016)
					(thickness 0.1524)
				)
			)
		)
		(property "Device Type" "SOD323AKH44"
			(at 0 -8.6868 90)
			(unlocked yes)
			(layer "F.Fab")
			(hide yes)
			(effects
				(font
					(size 1.016 1.016)
					(thickness 0.1524)
				)
			)
		)
		(duplicate_pad_numbers_are_jumpers no)
		(fp_line
			(start 0.889 -1.9304)
			(end 0.889 2.159)
			(stroke
				(width 0.1524)
				(type default)
			)
			(layer "F.SilkS")
		)
		(fp_line
			(start -0.889 -1.9304)
			(end 0.889 -1.9304)
			(stroke
				(width 0.1524)
				(type default)
			)
			(layer "F.SilkS")
		)
		(fp_line
			(start 0.762 2.0574)
			(end -0.762 2.0574)
			(stroke
				(width 0.508)
				(type default)
			)
			(layer "F.SilkS")
		)
		(fp_line
			(start 0.889 2.159)
			(end -0.889 2.159)
			(stroke
				(width 0.1524)
				(type default)
			)
			(layer "F.SilkS")
		)
		(fp_line
			(start -0.889 2.159)
			(end -0.889 -1.9304)
			(stroke
				(width 0.1524)
				(type default)
			)
			(layer "F.SilkS")
		)
		(fp_rect
			(start -1.016 2.3114)
			(end 1.016 -2.0066)
			(stroke
				(width 0)
				(type default)
			)
			(fill no)
			(layer "F.CrtYd")
		)
		(fp_poly
			(pts
				(xy -1.016 -2.0066) (xy 1.016 -2.0066) (xy 1.016 2.3114) (xy -1.016 2.3114)
			)
			(stroke
				(width 0)
				(type default)
			)
			(fill no)
			(layer "F.Fab")
		)
		(pad "A" smd rect
			(at 0 -1.143 90)
			(size 0.5588 1.016)
			(layers "F.Cu" "F.Mask" "F.Paste")
			(net "MB0_P12V_R")
		)
		(pad "K" smd rect
			(at 0 1.143 90)
			(size 0.5588 1.016)
			(layers "F.Cu" "F.Mask" "F.Paste")
			(net "MB0_CM_GATE_R")
		)
	)
	(footprint ""
		(layer "F.Cu")
		(at 195.4276 -26.8986)
		(property "Reference" "R837"
			(at 0 0 0)
			(layer "F.SilkS")
			(hide yes)
			(effects
				(font
					(size 1.27 1.27)
				)
			)
		)
		(property "Value" "4K7R2F-GP"
			(at 0.064008 -3.993896 0)
			(unlocked yes)
			(layer "F.Fab")
			(hide yes)
			(effects
				(font
					(size 1.016 1.016)
					(thickness 0.1524)
				)
			)
		)
		(property "Device Type" "R402H16"
			(at 0.064008 -5.517896 0)
			(unlocked yes)
			(layer "F.Fab")
			(hide yes)
			(effects
				(font
					(size 1.016 1.016)
					(thickness 0.1524)
				)
			)
		)
		(duplicate_pad_numbers_are_jumpers no)
		(fp_line
			(start -0.508 -0.9398)
			(end -0.508 0.9398)
			(stroke
				(width 0.1524)
				(type default)
			)
			(layer "F.SilkS")
		)
		(fp_line
			(start 0.508 -0.9398)
			(end -0.508 -0.9398)
			(stroke
				(width 0.1524)
				(type default)
			)
			(layer "F.SilkS")
		)
		(fp_rect
			(start -0.508 0.9398)
			(end 0.508 -0.9398)
			(stroke
				(width 0)
				(type default)
			)
			(fill no)
			(layer "F.CrtYd")
		)
		(fp_rect
			(start -0.508 0.9398)
			(end 0.508 -0.9398)
			(stroke
				(width 0)
				(type default)
			)
			(fill no)
			(layer "F.Fab")
		)
		(pad "1" smd custom
			(at 0 -0.4445)
			(size 0.1397 0.1397)
			(layers "F.Cu" "F.Mask" "F.Paste")
			(net "GND")
			(options
				(clearance outline)
				(anchor circle)
			)
			(primitives
				(gr_poly
					(pts
						(arc
							(start -0.1778 -0.2794)
							(mid -0.249642 -0.249642)
							(end -0.2794 -0.1778)
						)
						(arc
							(start -0.2794 0.1778)
							(mid -0.249642 0.249642)
							(end -0.1778 0.2794)
						)
						(arc
							(start 0.1778 0.2794)
							(mid 0.249642 0.249642)
							(end 0.2794 0.1778)
						)
						(arc
							(start 0.2794 -0.1778)
							(mid 0.249642 -0.249642)
							(end 0.1778 -0.2794)
						)
					)
					(width 0)
					(fill yes)
				)
			)
		)
		(pad "2" smd custom
			(at 0 0.4445)
			(size 0.1397 0.1397)
			(layers "F.Cu" "F.Mask" "F.Paste")
			(net "U56_A0")
			(options
				(clearance outline)
				(anchor circle)
			)
			(primitives
				(gr_poly
					(pts
						(arc
							(start -0.1778 -0.2794)
							(mid -0.249642 -0.249642)
							(end -0.2794 -0.1778)
						)
						(arc
							(start -0.2794 0.1778)
							(mid -0.249642 0.249642)
							(end -0.1778 0.2794)
						)
						(arc
							(start 0.1778 0.2794)
							(mid 0.249642 0.249642)
							(end 0.2794 0.1778)
						)
						(arc
							(start 0.2794 -0.1778)
							(mid 0.249642 -0.249642)
							(end 0.1778 -0.2794)
						)
					)
					(width 0)
					(fill yes)
				)
			)
		)
	)
	(footprint ""
		(layer "F.Cu")
		(at 93.407992 -212.420454 180)
		(property "Reference" "C379"
			(at 0 0 180)
			(layer "F.SilkS")
			(hide yes)
			(effects
				(font
					(size 1.27 1.27)
				)
			)
		)
		(property "Value" "SCD22U10V2KX-1GP"
			(at 1.1811 -2.7051 180)
			(unlocked yes)
			(layer "F.Fab")
			(hide yes)
			(effects
				(font
					(size 1.016 1.016)
					(thickness 0.1524)
				)
			)
		)
		(property "Device Type" "C402H22"
			(at 1.1811 -4.2291 180)
			(unlocked yes)
			(layer "F.Fab")
			(hide yes)
			(effects
				(font
					(size 1.016 1.016)
					(thickness 0.1524)
				)
			)
		)
		(duplicate_pad_numbers_are_jumpers no)
		(fp_rect
			(start -0.4318 0.9525)
			(end 0.4318 -0.9525)
			(stroke
				(width 0)
				(type default)
			)
			(fill no)
			(layer "F.CrtYd")
		)
		(fp_rect
			(start -0.4318 0.9525)
			(end 0.4318 -0.9525)
			(stroke
				(width 0)
				(type default)
			)
			(fill no)
			(layer "F.Fab")
		)
		(pad "1" smd custom
			(at 0 -0.4445 180)
			(size 0.1524 0.1524)
			(layers "F.Cu" "F.Mask" "F.Paste")
			(net "PCIE_TX_CAP_N64")
			(options
				(clearance outline)
				(anchor circle)
			)
			(primitives
				(gr_poly
					(pts
						(arc
							(start 0.3048 -0.2032)
							(mid 0.275042 -0.275042)
							(end 0.2032 -0.3048)
						)
						(arc
							(start -0.2032 -0.3048)
							(mid -0.275042 -0.275042)
							(end -0.3048 -0.2032)
						)
						(arc
							(start -0.3048 0.2032)
							(mid -0.275042 0.275042)
							(end -0.2032 0.3048)
						)
						(arc
							(start 0.2032 0.3048)
							(mid 0.275042 0.275042)
							(end 0.3048 0.2032)
						)
					)
					(width 0)
					(fill yes)
				)
			)
		)
		(pad "2" smd custom
			(at 0 0.4445 180)
			(size 0.1524 0.1524)
			(layers "F.Cu" "F.Mask" "F.Paste")
			(net "PCIE_TX_N64")
			(options
				(clearance outline)
				(anchor circle)
			)
			(primitives
				(gr_poly
					(pts
						(arc
							(start 0.3048 -0.2032)
							(mid 0.275042 -0.275042)
							(end 0.2032 -0.3048)
						)
						(arc
							(start -0.2032 -0.3048)
							(mid -0.275042 -0.275042)
							(end -0.3048 -0.2032)
						)
						(arc
							(start -0.3048 0.2032)
							(mid -0.275042 0.275042)
							(end -0.2032 0.3048)
						)
						(arc
							(start 0.2032 0.3048)
							(mid 0.275042 0.275042)
							(end 0.3048 0.2032)
						)
					)
					(width 0)
					(fill yes)
				)
			)
		)
	)
)
